# S9S_MB_2U (Grand Teton) — schematic netlist excerpt (pin names and nets, part order shuffled) for the footprints in the layout excerpt that follows; sources: Cadence DE-HDL packaged netlist, KiCad conversion of 03242023_DA0F0TMBIJ0_F0T_Motherboard_J_brd_V01_OCP.brd

R53  Q_RES  10 1% CHIP  pkg 0402LF  page 47 : A = DBP_CPU1_HOOK8_MBP2_GTL_QS_R_N ; B = DBP_CPU_HOOK8_MBP2_GTL_QS_N
C351  Q_CAP  47UF 4V 20% X6S  pkg C0805  page 78 : A = PVCCIN_CPU1 ; B = GND
R297  Q_RES  0 5% CHIP  pkg 0402LF  page 118 : A = H_CPU0_CATERR_LVC1_R_N ; B = H_CPU_CATERR_LVC1_R_N

(kicad_pcb
	(version 20260206)
	(generator "pcbnew")
	(generator_version "10.0")
	(general
		(thickness 1.6)
		(legacy_teardrops no)
	)
	(paper "A4")
	(title_block
		(title "03242023_DA0F0TMBIJ0_F0T_Motherboard_J_brd_V01_OCP.brd")
		(comment 1 "Grand Teton / footprints 5473-5475 of 6105")
	)
	(layers
		(0 "F.Cu" signal "TOP")
		(4 "In1.Cu" signal "GND")
		(6 "In2.Cu" signal "IN1")
		(8 "In3.Cu" signal "GND1")
		(10 "In4.Cu" signal "IN2")
		(12 "In5.Cu" signal "GND2")
		(14 "In6.Cu" signal "IN3")
		(16 "In7.Cu" signal "GND3")
		(18 "In8.Cu" signal "VCC")
		(20 "In9.Cu" signal "VCC1")
		(22 "In10.Cu" signal "GND4")
		(24 "In11.Cu" signal "IN4")
		(26 "In12.Cu" signal "GND5")
		(28 "In13.Cu" signal "IN5")
		(30 "In14.Cu" signal "GND6")
		(32 "In15.Cu" signal "IN6")
		(34 "In16.Cu" signal "GND7")
		(2 "B.Cu" signal "BOTTOM")
		(9 "F.Adhes" user "F.Adhesive")
		(11 "B.Adhes" user "B.Adhesive")
		(13 "F.Paste" user "Package Geometry/Pastemask Top")
		(15 "B.Paste" user "Package Geometry/Pastemask Bottom")
		(5 "F.SilkS" user "Ref Des/Silkscreen Top")
		(7 "B.SilkS" user "Ref Des/Silkscreen Bottom")
		(1 "F.Mask" user "Board Geometry/Soldermask Top")
		(3 "B.Mask" user "Board Geometry/Soldermask Bottom")
		(17 "Dwgs.User" user "User.Drawings")
		(19 "Cmts.User" user "User.Comments")
		(21 "Eco1.User" user "User.Eco1")
		(23 "Eco2.User" user "User.Eco2")
		(25 "Edge.Cuts" user "Board Geometry/Outline")
		(27 "Margin" user)
		(31 "F.CrtYd" user "Package Geometry/Place Bound Top")
		(29 "B.CrtYd" user "Package Geometry/Place Bound Bottom")
		(35 "F.Fab" user "Ref Des/Assembly Top")
		(33 "B.Fab" user "Ref Des/Assembly Bottom")
	)
	(footprint ""
		(layer "B.Cu")
		(at 329.170538 -186.36615 90)
		(property "Reference" "R297"
			(at 0 0 90)
			(layer "B.SilkS")
			(hide yes)
			(effects
				(font
					(size 1.27 1.27)
				)
				(justify mirror)
			)
		)
		(property "Value" ""
			(at 0 0 90)
			(layer "B.Fab")
			(effects
				(font
					(size 1.27 1.27)
				)
				(justify mirror)
			)
		)
		(duplicate_pad_numbers_are_jumpers no)
		(fp_line
			(start 0.7874 -0.4064)
			(end -0.7874 -0.4064)
			(stroke
				(width 0.1524)
				(type default)
			)
			(layer "B.SilkS")
		)
		(fp_line
			(start -0.7874 -0.4064)
			(end -0.7874 0.4064)
			(stroke
				(width 0.1524)
				(type default)
			)
			(layer "B.SilkS")
		)
		(fp_line
			(start 0.7874 0.4064)
			(end 0.7874 -0.4064)
			(stroke
				(width 0.1524)
				(type default)
			)
			(layer "B.SilkS")
		)
		(fp_line
			(start -0.7874 0.4064)
			(end 0.7874 0.4064)
			(stroke
				(width 0.1524)
				(type default)
			)
			(layer "B.SilkS")
		)
		(fp_line
			(start 0.67945 -0.305054)
			(end 0.12065 -0.305054)
			(stroke
				(width 0.1)
				(type default)
			)
			(layer "B.Fab")
		)
		(fp_line
			(start 0.12065 -0.305054)
			(end 0.12065 -0.2794)
			(stroke
				(width 0.1)
				(type default)
			)
			(layer "B.Fab")
		)
		(fp_line
			(start -0.12065 -0.3048)
			(end -0.67945 -0.3048)
			(stroke
				(width 0.1)
				(type default)
			)
			(layer "B.Fab")
		)
		(fp_line
			(start -0.67945 -0.3048)
			(end -0.67945 0.3048)
			(stroke
				(width 0.1)
				(type default)
			)
			(layer "B.Fab")
		)
		(fp_line
			(start 0.12065 -0.2794)
			(end -0.12065 -0.2794)
			(stroke
				(width 0.1)
				(type default)
			)
			(layer "B.Fab")
		)
		(fp_line
			(start -0.12065 -0.2794)
			(end -0.12065 -0.3048)
			(stroke
				(width 0.1)
				(type default)
			)
			(layer "B.Fab")
		)
		(fp_line
			(start 0.12065 0.2794)
			(end 0.12065 0.3048)
			(stroke
				(width 0.1)
				(type default)
			)
			(layer "B.Fab")
		)
		(fp_line
			(start -0.120396 0.2794)
			(end 0.12065 0.2794)
			(stroke
				(width 0.1)
				(type default)
			)
			(layer "B.Fab")
		)
		(fp_line
			(start 0.67945 0.3048)
			(end 0.67945 -0.305054)
			(stroke
				(width 0.1)
				(type default)
			)
			(layer "B.Fab")
		)
		(fp_line
			(start 0.12065 0.3048)
			(end 0.67945 0.3048)
			(stroke
				(width 0.1)
				(type default)
			)
			(layer "B.Fab")
		)
		(fp_line
			(start -0.120396 0.3048)
			(end -0.120396 0.2794)
			(stroke
				(width 0.1)
				(type default)
			)
			(layer "B.Fab")
		)
		(fp_line
			(start -0.67945 0.3048)
			(end -0.120396 0.3048)
			(stroke
				(width 0.1)
				(type default)
			)
			(layer "B.Fab")
		)
		(pad "1" smd circle
			(at 0.40005 0 270)
			(size 0 0)
			(layers "B.Cu" "B.Mask" "B.Paste")
			(net "H_CPU0_CATERR_LVC1_R_N")
		)
		(pad "2" smd circle
			(at -0.40005 0 270)
			(size 0 0)
			(layers "B.Cu" "B.Mask" "B.Paste")
			(net "H_CPU_CATERR_LVC1_R_N")
		)
	)
	(footprint ""
		(layer "B.Cu")
		(at 118.18112 -252.17628 -90)
		(property "Reference" "C351"
			(at 0 0 90)
			(layer "B.SilkS")
			(hide yes)
			(effects
				(font
					(size 1.27 1.27)
				)
				(justify mirror)
			)
		)
		(property "Value" ""
			(at 0 0 90)
			(layer "B.Fab")
			(effects
				(font
					(size 1.27 1.27)
				)
				(justify mirror)
			)
		)
		(duplicate_pad_numbers_are_jumpers no)
		(fp_line
			(start -1.524 0.762)
			(end 1.524 0.762)
			(stroke
				(width 0.1524)
				(type default)
			)
			(layer "B.SilkS")
		)
		(fp_line
			(start 1.524 0.762)
			(end 1.524 -0.762)
			(stroke
				(width 0.1524)
				(type default)
			)
			(layer "B.SilkS")
		)
		(fp_line
			(start -1.524 -0.762)
			(end -1.524 0.762)
			(stroke
				(width 0.1524)
				(type default)
			)
			(layer "B.SilkS")
		)
		(fp_line
			(start 1.524 -0.762)
			(end -1.524 -0.762)
			(stroke
				(width 0.1524)
				(type default)
			)
			(layer "B.SilkS")
		)
		(fp_line
			(start -1.1049 0.724916)
			(end -1.1049 -0.724916)
			(stroke
				(width 0.1)
				(type default)
			)
			(layer "B.Fab")
		)
		(fp_line
			(start 1.1049 0.724916)
			(end -1.1049 0.724916)
			(stroke
				(width 0.1)
				(type default)
			)
			(layer "B.Fab")
		)
		(fp_line
			(start -1.1049 -0.724916)
			(end 1.1049 -0.724916)
			(stroke
				(width 0.1)
				(type default)
			)
			(layer "B.Fab")
		)
		(fp_line
			(start 1.1049 -0.724916)
			(end 1.1049 0.724916)
			(stroke
				(width 0.1)
				(type default)
			)
			(layer "B.Fab")
		)
		(pad "1" smd rect
			(at 0.889 0 270)
			(size 1.016 1.27)
			(layers "B.Cu" "B.Mask" "B.Paste")
			(net "PVCCIN_CPU1")
		)
		(pad "2" smd rect
			(at -0.889 0 270)
			(size 1.016 1.27)
			(layers "B.Cu" "B.Mask" "B.Paste")
			(net "GND")
		)
	)
	(footprint ""
		(layer "B.Cu")
		(at 70.369684 -183.303926 90)
		(property "Reference" "R53"
			(at 0 0 90)
			(layer "B.SilkS")
			(hide yes)
			(effects
				(font
					(size 1.27 1.27)
				)
				(justify mirror)
			)
		)
		(property "Value" ""
			(at 0 0 90)
			(layer "B.Fab")
			(effects
				(font
					(size 1.27 1.27)
				)
				(justify mirror)
			)
		)
		(duplicate_pad_numbers_are_jumpers no)
		(fp_line
			(start 0.7874 -0.4064)
			(end -0.7874 -0.4064)
			(stroke
				(width 0.1524)
				(type default)
			)
			(layer "B.SilkS")
		)
		(fp_line
			(start -0.7874 -0.4064)
			(end -0.7874 0.4064)
			(stroke
				(width 0.1524)
				(type default)
			)
			(layer "B.SilkS")
		)
		(fp_line
			(start 0.7874 0.4064)
			(end 0.7874 -0.4064)
			(stroke
				(width 0.1524)
				(type default)
			)
			(layer "B.SilkS")
		)
		(fp_line
			(start -0.7874 0.4064)
			(end 0.7874 0.4064)
			(stroke
				(width 0.1524)
				(type default)
			)
			(layer "B.SilkS")
		)
		(fp_line
			(start 0.67945 -0.305054)
			(end 0.12065 -0.305054)
			(stroke
				(width 0.1)
				(type default)
			)
			(layer "B.Fab")
		)
		(fp_line
			(start 0.12065 -0.305054)
			(end 0.12065 -0.2794)
			(stroke
				(width 0.1)
				(type default)
			)
			(layer "B.Fab")
		)
		(fp_line
			(start -0.12065 -0.3048)
			(end -0.67945 -0.3048)
			(stroke
				(width 0.1)
				(type default)
			)
			(layer "B.Fab")
		)
		(fp_line
			(start -0.67945 -0.3048)
			(end -0.67945 0.3048)
			(stroke
				(width 0.1)
				(type default)
			)
			(layer "B.Fab")
		)
		(fp_line
			(start 0.12065 -0.2794)
			(end -0.12065 -0.2794)
			(stroke
				(width 0.1)
				(type default)
			)
			(layer "B.Fab")
		)
		(fp_line
			(start -0.12065 -0.2794)
			(end -0.12065 -0.3048)
			(stroke
				(width 0.1)
				(type default)
			)
			(layer "B.Fab")
		)
		(fp_line
			(start 0.12065 0.2794)
			(end 0.12065 0.3048)
			(stroke
				(width 0.1)
				(type default)
			)
			(layer "B.Fab")
		)
		(fp_line
			(start -0.120396 0.2794)
			(end 0.12065 0.2794)
			(stroke
				(width 0.1)
				(type default)
			)
			(layer "B.Fab")
		)
		(fp_line
			(start 0.67945 0.3048)
			(end 0.67945 -0.305054)
			(stroke
				(width 0.1)
				(type default)
			)
			(layer "B.Fab")
		)
		(fp_line
			(start 0.12065 0.3048)
			(end 0.67945 0.3048)
			(stroke
				(width 0.1)
				(type default)
			)
			(layer "B.Fab")
		)
		(fp_line
			(start -0.120396 0.3048)
			(end -0.120396 0.2794)
			(stroke
				(width 0.1)
				(type default)
			)
			(layer "B.Fab")
		)
		(fp_line
			(start -0.67945 0.3048)
			(end -0.120396 0.3048)
			(stroke
				(width 0.1)
				(type default)
			)
			(layer "B.Fab")
		)
		(pad "1" smd circle
			(at 0.40005 0 270)
			(size 0 0)
			(layers "B.Cu" "B.Mask" "B.Paste")
			(net "DBP_CPU1_HOOK8_MBP2_GTL_QS_R_N")
		)
		(pad "2" smd circle
			(at -0.40005 0 270)
			(size 0 0)
			(layers "B.Cu" "B.Mask" "B.Paste")
			(net "DBP_CPU_HOOK8_MBP2_GTL_QS_N")
		)
	)
)
